(kicad_pcb
	(version 20260206)
	(generator "pcbnew")
	(generator_version "10.0")
	(general
		(thickness 1.6)
		(legacy_teardrops no)
	)
	(paper "A4")
	(title_block
		(title "Bryce Canyon_SCC_16316-1_OCP.brd")
		(comment 1 "Bryce Canyon / footprints 1182-1189 of 1561")
	)
	(layers
		(0 "F.Cu" signal "TOP")
		(4 "In1.Cu" signal "L2GND")
		(6 "In2.Cu" signal "L3")
		(8 "In3.Cu" signal "L4VCC")
		(10 "In4.Cu" signal "L5VCC")
		(12 "In5.Cu" signal "L6")
		(14 "In6.Cu" signal "L7GND")
		(2 "B.Cu" signal "BOTTOM")
		(9 "F.Adhes" user "F.Adhesive")
		(11 "B.Adhes" user "B.Adhesive")
		(13 "F.Paste" user "Package Geometry/Pastemask Top")
		(15 "B.Paste" user "Package Geometry/Pastemask Bottom")
		(5 "F.SilkS" user "Ref Des/Silkscreen Top")
		(7 "B.SilkS" user "Ref Des/Silkscreen Bottom")
		(1 "F.Mask" user "Board Geometry/Soldermask Top")
		(3 "B.Mask" user "Board Geometry/Soldermask Bottom")
		(17 "Dwgs.User" user "User.Drawings")
		(19 "Cmts.User" user "User.Comments")
		(21 "Eco1.User" user "User.Eco1")
		(23 "Eco2.User" user "User.Eco2")
		(25 "Edge.Cuts" user "Board Geometry/Outline")
		(27 "Margin" user)
		(31 "F.CrtYd" user "Package Geometry/Place Bound Top")
		(29 "B.CrtYd" user "Package Geometry/Place Bound Bottom")
		(35 "F.Fab" user "Ref Des/Assembly Top")
		(33 "B.Fab" user "Ref Des/Assembly Bottom")
	)
	(footprint ""
		(layer "B.Cu")
		(at 200.66 -24.257 180)
		(property "Reference" "LED2"
			(at 0 0 0)
			(layer "B.SilkS")
			(hide yes)
			(effects
				(font
					(size 1.27 1.27)
				)
				(justify mirror)
			)
		)
		(property "Value" "LED-YG-51-GP"
			(at 2.6924 -1.4224 180)
			(unlocked yes)
			(layer "B.Fab")
			(hide yes)
			(effects
				(font
					(size 1.016 1.016)
					(thickness 0.1524)
				)
				(justify mirror)
			)
		)
		(property "Device Type" "LED1608AKH40"
			(at 2.6924 -2.9464 180)
			(unlocked yes)
			(layer "B.Fab")
			(hide yes)
			(effects
				(font
					(size 1.016 1.016)
					(thickness 0.1524)
				)
				(justify mirror)
			)
		)
		(duplicate_pad_numbers_are_jumpers no)
		(fp_line
			(start 0.7493 1.651)
			(end 0.7493 1.1811)
			(stroke
				(width 0.3302)
				(type default)
			)
			(layer "B.SilkS")
		)
		(fp_line
			(start 0.6604 1.3716)
			(end 0.6604 -1.3716)
			(stroke
				(width 0.1524)
				(type default)
			)
			(layer "B.SilkS")
		)
		(fp_line
			(start 0.6604 -1.3716)
			(end -0.6604 -1.3716)
			(stroke
				(width 0.1524)
				(type default)
			)
			(layer "B.SilkS")
		)
		(fp_line
			(start 0.5969 1.5494)
			(end -0.5842 1.5494)
			(stroke
				(width 0.508)
				(type default)
			)
			(layer "B.SilkS")
		)
		(fp_line
			(start -0.6604 1.3716)
			(end 0.6604 1.3716)
			(stroke
				(width 0.1524)
				(type default)
			)
			(layer "B.SilkS")
		)
		(fp_line
			(start -0.6604 -1.3716)
			(end -0.6604 1.3716)
			(stroke
				(width 0.1524)
				(type default)
			)
			(layer "B.SilkS")
		)
		(fp_line
			(start -0.7493 1.651)
			(end -0.7493 1.1811)
			(stroke
				(width 0.3302)
				(type default)
			)
			(layer "B.SilkS")
		)
		(fp_rect
			(start 0.6223 1.3335)
			(end -0.6223 -1.3335)
			(stroke
				(width 0)
				(type default)
			)
			(fill no)
			(layer "B.CrtYd")
		)
		(fp_rect
			(start 0.6223 1.3335)
			(end -0.6223 -1.3335)
			(stroke
				(width 0)
				(type default)
			)
			(fill no)
			(layer "B.Fab")
		)
		(pad "A" smd custom
			(at 0 -0.762)
			(size 0.2159 0.2159)
			(layers "B.Cu" "B.Mask" "B.Paste")
			(net "SYS_ERROR_LED_R")
			(options
				(clearance outline)
				(anchor circle)
			)
			(primitives
				(gr_poly
					(pts
						(arc
							(start -0.3302 0.4318)
							(mid -0.402042 0.402042)
							(end -0.4318 0.3302)
						)
						(arc
							(start -0.4318 -0.3302)
							(mid -0.402042 -0.402042)
							(end -0.3302 -0.4318)
						)
						(arc
							(start 0.3302 -0.4318)
							(mid 0.402042 -0.402042)
							(end 0.4318 -0.3302)
						)
						(arc
							(start 0.4318 0.3302)
							(mid 0.402042 0.402042)
							(end 0.3302 0.4318)
						)
					)
					(width 0)
					(fill yes)
				)
			)
		)
		(pad "K" smd custom
			(at 0 0.762)
			(size 0.2159 0.2159)
			(layers "B.Cu" "B.Mask" "B.Paste")
			(net "SYS_ERROR_LED_D")
			(options
				(clearance outline)
				(anchor circle)
			)
			(primitives
				(gr_poly
					(pts
						(arc
							(start -0.3302 0.4318)
							(mid -0.402042 0.402042)
							(end -0.4318 0.3302)
						)
						(arc
							(start -0.4318 -0.3302)
							(mid -0.402042 -0.402042)
							(end -0.3302 -0.4318)
						)
						(arc
							(start 0.3302 -0.4318)
							(mid 0.402042 -0.402042)
							(end 0.4318 -0.3302)
						)
						(arc
							(start 0.4318 0.3302)
							(mid 0.402042 0.402042)
							(end 0.3302 0.4318)
						)
					)
					(width 0)
					(fill yes)
				)
			)
		)
	)
	(footprint ""
		(layer "B.Cu")
		(at 196.088 -28.321 180)
		(property "Reference" "C379"
			(at 0 0 0)
			(layer "B.SilkS")
			(hide yes)
			(effects
				(font
					(size 1.27 1.27)
				)
				(justify mirror)
			)
		)
		(property "Value" "SC1U16V2KX-7-GP"
			(at -1.7526 -1.6002 180)
			(unlocked yes)
			(layer "B.Fab")
			(hide yes)
			(effects
				(font
					(size 1.016 1.016)
					(thickness 0.1524)
				)
				(justify mirror)
			)
		)
		(property "Device Type" "C402-TO0D2H24"
			(at -1.7526 -3.1242 180)
			(unlocked yes)
			(layer "B.Fab")
			(hide yes)
			(effects
				(font
					(size 1.016 1.016)
					(thickness 0.1524)
				)
				(justify mirror)
			)
		)
		(duplicate_pad_numbers_are_jumpers no)
		(fp_rect
			(start 0.4826 0.889)
			(end -0.4826 -0.889)
			(stroke
				(width 0)
				(type default)
			)
			(fill no)
			(layer "B.CrtYd")
		)
		(fp_rect
			(start 0.4826 0.889)
			(end -0.4826 -0.889)
			(stroke
				(width 0)
				(type default)
			)
			(fill no)
			(layer "B.Fab")
		)
		(pad "1" smd custom
			(at 0 -0.4572)
			(size 0.1524 0.1524)
			(layers "B.Cu" "B.Mask" "B.Paste")
			(net "PCE_VDDH")
			(options
				(clearance outline)
				(anchor circle)
			)
			(primitives
				(gr_poly
					(pts
						(arc
							(start -0.254 -0.3048)
							(mid -0.325842 -0.275042)
							(end -0.3556 -0.2032)
						)
						(arc
							(start -0.3556 0.2032)
							(mid -0.325842 0.275042)
							(end -0.254 0.3048)
						)
						(arc
							(start 0.254 0.3048)
							(mid 0.325842 0.275042)
							(end 0.3556 0.2032)
						)
						(arc
							(start 0.3556 -0.2032)
							(mid 0.325842 -0.275042)
							(end 0.254 -0.3048)
						)
					)
					(width 0)
					(fill yes)
				)
			)
		)
		(pad "2" smd custom
			(at 0 0.4572)
			(size 0.1524 0.1524)
			(layers "B.Cu" "B.Mask" "B.Paste")
			(net "GND")
			(options
				(clearance outline)
				(anchor circle)
			)
			(primitives
				(gr_poly
					(pts
						(arc
							(start -0.254 -0.3048)
							(mid -0.325842 -0.275042)
							(end -0.3556 -0.2032)
						)
						(arc
							(start -0.3556 0.2032)
							(mid -0.325842 0.275042)
							(end -0.254 0.3048)
						)
						(arc
							(start 0.254 0.3048)
							(mid 0.325842 0.275042)
							(end 0.3556 0.2032)
						)
						(arc
							(start 0.3556 -0.2032)
							(mid 0.325842 -0.275042)
							(end 0.254 -0.3048)
						)
					)
					(width 0)
					(fill yes)
				)
			)
		)
	)
	(footprint ""
		(layer "B.Cu")
		(at 137.414 -74.041 -90)
		(property "Reference" "C10"
			(at 0 0 90)
			(layer "B.SilkS")
			(hide yes)
			(effects
				(font
					(size 1.27 1.27)
				)
				(justify mirror)
			)
		)
		(property "Value" "SCD01U16V1KX-GP"
			(at 2.8321 -1.7399 270)
			(unlocked yes)
			(layer "B.Fab")
			(hide yes)
			(effects
				(font
					(size 1.016 1.016)
					(thickness 0.1524)
				)
				(justify mirror)
			)
		)
		(property "Device Type" "C0201H13"
			(at 2.8321 -3.2639 270)
			(unlocked yes)
			(layer "B.Fab")
			(hide yes)
			(effects
				(font
					(size 1.016 1.016)
					(thickness 0.1524)
				)
				(justify mirror)
			)
		)
		(duplicate_pad_numbers_are_jumpers no)
		(fp_rect
			(start 0.2794 0.6477)
			(end -0.2794 -0.6477)
			(stroke
				(width 0)
				(type default)
			)
			(fill no)
			(layer "B.CrtYd")
		)
		(fp_rect
			(start 0.2794 0.6477)
			(end -0.2794 -0.6477)
			(stroke
				(width 0)
				(type default)
			)
			(fill no)
			(layer "B.Fab")
		)
		(pad "1" smd custom
			(at 0 -0.2794 90)
			(size 0.0762 0.0762)
			(layers "B.Cu" "B.Mask" "B.Paste")
			(net "PHY_DPB_TO_SCC_7_DN")
			(options
				(clearance outline)
				(anchor circle)
			)
			(primitives
				(gr_poly
					(pts
						(arc
							(start 0.1524 0.127)
							(mid 0.137521 0.162921)
							(end 0.1016 0.1778)
						)
						(arc
							(start -0.1016 0.1778)
							(mid -0.137521 0.162921)
							(end -0.1524 0.127)
						)
						(arc
							(start -0.1524 -0.127)
							(mid -0.137521 -0.162921)
							(end -0.1016 -0.1778)
						)
						(arc
							(start 0.1016 -0.1778)
							(mid 0.137521 -0.162921)
							(end 0.1524 -0.127)
						)
					)
					(width 0)
					(fill yes)
				)
			)
		)
		(pad "2" smd custom
			(at 0 0.2794 90)
			(size 0.0762 0.0762)
			(layers "B.Cu" "B.Mask" "B.Paste")
			(net "PHY_DPB_TO_SCC_C_7_DN")
			(options
				(clearance outline)
				(anchor circle)
			)
			(primitives
				(gr_poly
					(pts
						(arc
							(start 0.1524 0.127)
							(mid 0.137521 0.162921)
							(end 0.1016 0.1778)
						)
						(arc
							(start -0.1016 0.1778)
							(mid -0.137521 0.162921)
							(end -0.1524 0.127)
						)
						(arc
							(start -0.1524 -0.127)
							(mid -0.137521 -0.162921)
							(end -0.1016 -0.1778)
						)
						(arc
							(start 0.1016 -0.1778)
							(mid 0.137521 -0.162921)
							(end 0.1524 -0.127)
						)
					)
					(width 0)
					(fill yes)
				)
			)
		)
	)
	(footprint ""
		(layer "B.Cu")
		(at 104.8258 -44.2214 180)
		(property "Reference" "C78"
			(at 0 0 0)
			(layer "B.SilkS")
			(hide yes)
			(effects
				(font
					(size 1.27 1.27)
				)
				(justify mirror)
			)
		)
		(property "Value" "SCD01U16V1KX-GP"
			(at 2.8321 -1.7399 180)
			(unlocked yes)
			(layer "B.Fab")
			(hide yes)
			(effects
				(font
					(size 1.016 1.016)
					(thickness 0.1524)
				)
				(justify mirror)
			)
		)
		(property "Device Type" "C0201H13"
			(at 2.8321 -3.2639 180)
			(unlocked yes)
			(layer "B.Fab")
			(hide yes)
			(effects
				(font
					(size 1.016 1.016)
					(thickness 0.1524)
				)
				(justify mirror)
			)
		)
		(duplicate_pad_numbers_are_jumpers no)
		(fp_rect
			(start 0.2794 0.6477)
			(end -0.2794 -0.6477)
			(stroke
				(width 0)
				(type default)
			)
			(fill no)
			(layer "B.CrtYd")
		)
		(fp_rect
			(start 0.2794 0.6477)
			(end -0.2794 -0.6477)
			(stroke
				(width 0)
				(type default)
			)
			(fill no)
			(layer "B.Fab")
		)
		(pad "1" smd custom
			(at 0 -0.2794)
			(size 0.0762 0.0762)
			(layers "B.Cu" "B.Mask" "B.Paste")
			(net "PHY_DPB_TO_SCC_21_DP")
			(options
				(clearance outline)
				(anchor circle)
			)
			(primitives
				(gr_poly
					(pts
						(arc
							(start 0.1524 0.127)
							(mid 0.137521 0.162921)
							(end 0.1016 0.1778)
						)
						(arc
							(start -0.1016 0.1778)
							(mid -0.137521 0.162921)
							(end -0.1524 0.127)
						)
						(arc
							(start -0.1524 -0.127)
							(mid -0.137521 -0.162921)
							(end -0.1016 -0.1778)
						)
						(arc
							(start 0.1016 -0.1778)
							(mid 0.137521 -0.162921)
							(end 0.1524 -0.127)
						)
					)
					(width 0)
					(fill yes)
				)
			)
		)
		(pad "2" smd custom
			(at 0 0.2794)
			(size 0.0762 0.0762)
			(layers "B.Cu" "B.Mask" "B.Paste")
			(net "PHY_DPB_TO_SCC_C_21_DP")
			(options
				(clearance outline)
				(anchor circle)
			)
			(primitives
				(gr_poly
					(pts
						(arc
							(start 0.1524 0.127)
							(mid 0.137521 0.162921)
							(end 0.1016 0.1778)
						)
						(arc
							(start -0.1016 0.1778)
							(mid -0.137521 0.162921)
							(end -0.1524 0.127)
						)
						(arc
							(start -0.1524 -0.127)
							(mid -0.137521 -0.162921)
							(end -0.1016 -0.1778)
						)
						(arc
							(start 0.1016 -0.1778)
							(mid 0.137521 -0.162921)
							(end 0.1524 -0.127)
						)
					)
					(width 0)
					(fill yes)
				)
			)
		)
	)
	(footprint ""
		(layer "B.Cu")
		(at 138.50493 -119.731282 -90)
		(property "Reference" "C608"
			(at 0 0 90)
			(layer "B.SilkS")
			(hide yes)
			(effects
				(font
					(size 1.27 1.27)
				)
				(justify mirror)
			)
		)
		(property "Value" "SCD47U25V3KX-3-GP"
			(at 0 -2.8194 270)
			(unlocked yes)
			(layer "B.Fab")
			(hide yes)
			(effects
				(font
					(size 1.016 1.016)
					(thickness 0.1524)
				)
				(justify mirror)
			)
		)
		(property "Device Type" "C603H36"
			(at 0 -4.3434 270)
			(unlocked yes)
			(layer "B.Fab")
			(hide yes)
			(effects
				(font
					(size 1.016 1.016)
					(thickness 0.1524)
				)
				(justify mirror)
			)
		)
		(duplicate_pad_numbers_are_jumpers no)
		(fp_line
			(start -0.508 0)
			(end 0.508 0)
			(stroke
				(width 0.2032)
				(type default)
			)
			(layer "B.SilkS")
		)
		(fp_rect
			(start 0.5842 1.3335)
			(end -0.5842 -1.3335)
			(stroke
				(width 0)
				(type default)
			)
			(fill no)
			(layer "B.CrtYd")
		)
		(fp_rect
			(start 0.5842 1.3335)
			(end -0.5842 -1.3335)
			(stroke
				(width 0)
				(type default)
			)
			(fill no)
			(layer "B.Fab")
		)
		(pad "1" smd custom
			(at 0 -0.762 90)
			(size 0.2159 0.2159)
			(layers "B.Cu" "B.Mask" "B.Paste")
			(net "P1V5_C_PG_G")
			(options
				(clearance outline)
				(anchor circle)
			)
			(primitives
				(gr_poly
					(pts
						(arc
							(start -0.3302 0.4318)
							(mid -0.402042 0.402042)
							(end -0.4318 0.3302)
						)
						(arc
							(start -0.4318 -0.3302)
							(mid -0.402042 -0.402042)
							(end -0.3302 -0.4318)
						)
						(arc
							(start 0.3302 -0.4318)
							(mid 0.402042 -0.402042)
							(end 0.4318 -0.3302)
						)
						(arc
							(start 0.4318 0.3302)
							(mid 0.402042 0.402042)
							(end 0.3302 0.4318)
						)
					)
					(width 0)
					(fill yes)
				)
			)
		)
		(pad "2" smd custom
			(at 0 0.762 90)
			(size 0.2159 0.2159)
			(layers "B.Cu" "B.Mask" "B.Paste")
			(net "P1V5_C")
			(options
				(clearance outline)
				(anchor circle)
			)
			(primitives
				(gr_poly
					(pts
						(arc
							(start -0.3302 0.4318)
							(mid -0.402042 0.402042)
							(end -0.4318 0.3302)
						)
						(arc
							(start -0.4318 -0.3302)
							(mid -0.402042 -0.402042)
							(end -0.3302 -0.4318)
						)
						(arc
							(start 0.3302 -0.4318)
							(mid 0.402042 -0.402042)
							(end 0.4318 -0.3302)
						)
						(arc
							(start 0.4318 0.3302)
							(mid 0.402042 0.402042)
							(end 0.3302 0.4318)
						)
					)
					(width 0)
					(fill yes)
				)
			)
		)
	)
	(footprint ""
		(layer "B.Cu")
		(at 171.167298 -34.108644 180)
		(property "Reference" "C390"
			(at 0 0 0)
			(layer "B.SilkS")
			(hide yes)
			(effects
				(font
					(size 1.27 1.27)
				)
				(justify mirror)
			)
		)
		(property "Value" "SCD1U6D3V1KX-GP"
			(at 2.8321 -1.7399 180)
			(unlocked yes)
			(layer "B.Fab")
			(hide yes)
			(effects
				(font
					(size 1.016 1.016)
					(thickness 0.1524)
				)
				(justify mirror)
			)
		)
		(property "Device Type" "C0201H13"
			(at 2.8321 -3.2639 180)
			(unlocked yes)
			(layer "B.Fab")
			(hide yes)
			(effects
				(font
					(size 1.016 1.016)
					(thickness 0.1524)
				)
				(justify mirror)
			)
		)
		(duplicate_pad_numbers_are_jumpers no)
		(fp_rect
			(start 0.2794 0.6477)
			(end -0.2794 -0.6477)
			(stroke
				(width 0)
				(type default)
			)
			(fill no)
			(layer "B.CrtYd")
		)
		(fp_rect
			(start 0.2794 0.6477)
			(end -0.2794 -0.6477)
			(stroke
				(width 0)
				(type default)
			)
			(fill no)
			(layer "B.Fab")
		)
		(pad "1" smd custom
			(at 0 -0.2794)
			(size 0.0762 0.0762)
			(layers "B.Cu" "B.Mask" "B.Paste")
			(net "PCE_AVDD")
			(options
				(clearance outline)
				(anchor circle)
			)
			(primitives
				(gr_poly
					(pts
						(arc
							(start 0.1524 0.127)
							(mid 0.137521 0.162921)
							(end 0.1016 0.1778)
						)
						(arc
							(start -0.1016 0.1778)
							(mid -0.137521 0.162921)
							(end -0.1524 0.127)
						)
						(arc
							(start -0.1524 -0.127)
							(mid -0.137521 -0.162921)
							(end -0.1016 -0.1778)
						)
						(arc
							(start 0.1016 -0.1778)
							(mid 0.137521 -0.162921)
							(end 0.1524 -0.127)
						)
					)
					(width 0)
					(fill yes)
				)
			)
		)
		(pad "2" smd custom
			(at 0 0.2794)
			(size 0.0762 0.0762)
			(layers "B.Cu" "B.Mask" "B.Paste")
			(net "GND")
			(options
				(clearance outline)
				(anchor circle)
			)
			(primitives
				(gr_poly
					(pts
						(arc
							(start 0.1524 0.127)
							(mid 0.137521 0.162921)
							(end 0.1016 0.1778)
						)
						(arc
							(start -0.1016 0.1778)
							(mid -0.137521 0.162921)
							(end -0.1524 0.127)
						)
						(arc
							(start -0.1524 -0.127)
							(mid -0.137521 -0.162921)
							(end -0.1016 -0.1778)
						)
						(arc
							(start 0.1016 -0.1778)
							(mid 0.137521 -0.162921)
							(end 0.1524 -0.127)
						)
					)
					(width 0)
					(fill yes)
				)
			)
		)
	)
	(footprint ""
		(layer "B.Cu")
		(at 191.953134 -36.8427 -90)
		(property "Reference" "R185"
			(at 0 0 90)
			(layer "B.SilkS")
			(hide yes)
			(effects
				(font
					(size 1.27 1.27)
				)
				(justify mirror)
			)
		)
		(property "Value" "2K2R2F-GP"
			(at -0.064008 -3.993896 270)
			(unlocked yes)
			(layer "B.Fab")
			(hide yes)
			(effects
				(font
					(size 1.016 1.016)
					(thickness 0.1524)
				)
				(justify mirror)
			)
		)
		(property "Device Type" "R402H16"
			(at -0.064008 -5.517896 270)
			(unlocked yes)
			(layer "B.Fab")
			(hide yes)
			(effects
				(font
					(size 1.016 1.016)
					(thickness 0.1524)
				)
				(justify mirror)
			)
		)
		(duplicate_pad_numbers_are_jumpers no)
		(fp_line
			(start -0.508 -0.9398)
			(end 0.508 -0.9398)
			(stroke
				(width 0.1524)
				(type default)
			)
			(layer "B.SilkS")
		)
		(fp_line
			(start 0.508 -0.9398)
			(end 0.508 0.9398)
			(stroke
				(width 0.1524)
				(type default)
			)
			(layer "B.SilkS")
		)
		(fp_rect
			(start 0.508 0.9398)
			(end -0.508 -0.9398)
			(stroke
				(width 0)
				(type default)
			)
			(fill no)
			(layer "B.CrtYd")
		)
		(fp_rect
			(start 0.508 0.9398)
			(end -0.508 -0.9398)
			(stroke
				(width 0)
				(type default)
			)
			(fill no)
			(layer "B.Fab")
		)
		(pad "1" smd custom
			(at 0 -0.4445 90)
			(size 0.1397 0.1397)
			(layers "B.Cu" "B.Mask" "B.Paste")
			(net "P1V8_C")
			(options
				(clearance outline)
				(anchor circle)
			)
			(primitives
				(gr_poly
					(pts
						(arc
							(start -0.1778 0.2794)
							(mid -0.249642 0.249642)
							(end -0.2794 0.1778)
						)
						(arc
							(start -0.2794 -0.1778)
							(mid -0.249642 -0.249642)
							(end -0.1778 -0.2794)
						)
						(arc
							(start 0.1778 -0.2794)
							(mid 0.249642 -0.249642)
							(end 0.2794 -0.1778)
						)
						(arc
							(start 0.2794 0.1778)
							(mid 0.249642 0.249642)
							(end 0.1778 0.2794)
						)
					)
					(width 0)
					(fill yes)
				)
			)
		)
		(pad "2" smd custom
			(at 0 0.4445 90)
			(size 0.1397 0.1397)
			(layers "B.Cu" "B.Mask" "B.Paste")
			(net "I2C_IOC_2_SCL")
			(options
				(clearance outline)
				(anchor circle)
			)
			(primitives
				(gr_poly
					(pts
						(arc
							(start -0.1778 0.2794)
							(mid -0.249642 0.249642)
							(end -0.2794 0.1778)
						)
						(arc
							(start -0.2794 -0.1778)
							(mid -0.249642 -0.249642)
							(end -0.1778 -0.2794)
						)
						(arc
							(start 0.1778 -0.2794)
							(mid 0.249642 -0.249642)
							(end 0.2794 -0.1778)
						)
						(arc
							(start 0.2794 0.1778)
							(mid 0.249642 0.249642)
							(end 0.1778 0.2794)
						)
					)
					(width 0)
					(fill yes)
				)
			)
		)
	)
	(footprint ""
		(layer "B.Cu")
		(at 188.341 -37.211 90)
		(property "Reference" "TP77"
			(at 0 0 90)
			(layer "B.SilkS")
			(hide yes)
			(effects
				(font
					(size 1.27 1.27)
				)
				(justify mirror)
			)
		)
		(property "Value" "TPAD28-2-GP"
			(at 0.0127 -1.6637 90)
			(unlocked yes)
			(layer "B.Fab")
			(hide yes)
			(effects
				(font
					(size 1.016 1.016)
					(thickness 0.1524)
				)
				(justify mirror)
			)
		)
		(property "Device Type" "TPAD28"
			(at 0.0127 -3.1877 90)
			(unlocked yes)
			(layer "B.Fab")
			(hide yes)
			(effects
				(font
					(size 1.016 1.016)
					(thickness 0.1524)
				)
				(justify mirror)
			)
		)
		(duplicate_pad_numbers_are_jumpers no)
		(fp_poly
			(pts
				(arc
					(start 0 0.3556)
					(mid 0 -0.3556)
					(end 0 0.3556)
				)
			)
			(stroke
				(width 0)
				(type default)
			)
			(fill no)
			(layer "B.CrtYd")
		)
		(fp_poly
			(pts
				(arc
					(start 0 0.6096)
					(mid 0 -0.6096)
					(end 0 0.6096)
				)
			)
			(stroke
				(width 0)
				(type default)
			)
			(fill no)
			(layer "B.Fab")
		)
		(pad "1" smd circle
			(at 0 0 270)
			(size 0.7112 0.7112)
			(layers "B.Cu" "B.Mask" "B.Paste")
			(net "IOC_GPIO_24")
		)
	)
)
